# S9S_MB_2U (Grand Teton) — schematic netlist excerpt (pin names and nets, part order shuffled) for the footprints in the layout excerpt that follows; sources: Cadence DE-HDL packaged netlist, KiCad conversion of 03242023_DA0F0TMBIJ0_F0T_Motherboard_J_brd_V01_OCP.brd

R3785  Q_RES  0 5% CHIP  pkg 0402LF  page 156 : A = P3V3_OCP_UV_1_R1 ; B = P3V3_OCP_UV_1
C1256  Q_CAP  1UF 6.3V 10% EMPTY  pkg 0402  page 189 : A = P1V05_PCH_PLL_AUX ; B = GND

(kicad_pcb
	(version 20260206)
	(generator "pcbnew")
	(generator_version "10.0")
	(general
		(thickness 1.6)
		(legacy_teardrops no)
	)
	(paper "A4")
	(title_block
		(title "03242023_DA0F0TMBIJ0_F0T_Motherboard_J_brd_V01_OCP.brd")
		(comment 1 "Grand Teton / footprints 5150-5151 of 6105")
	)
	(layers
		(0 "F.Cu" signal "TOP")
		(4 "In1.Cu" signal "GND")
		(6 "In2.Cu" signal "IN1")
		(8 "In3.Cu" signal "GND1")
		(10 "In4.Cu" signal "IN2")
		(12 "In5.Cu" signal "GND2")
		(14 "In6.Cu" signal "IN3")
		(16 "In7.Cu" signal "GND3")
		(18 "In8.Cu" signal "VCC")
		(20 "In9.Cu" signal "VCC1")
		(22 "In10.Cu" signal "GND4")
		(24 "In11.Cu" signal "IN4")
		(26 "In12.Cu" signal "GND5")
		(28 "In13.Cu" signal "IN5")
		(30 "In14.Cu" signal "GND6")
		(32 "In15.Cu" signal "IN6")
		(34 "In16.Cu" signal "GND7")
		(2 "B.Cu" signal "BOTTOM")
		(9 "F.Adhes" user "F.Adhesive")
		(11 "B.Adhes" user "B.Adhesive")
		(13 "F.Paste" user "Package Geometry/Pastemask Top")
		(15 "B.Paste" user "Package Geometry/Pastemask Bottom")
		(5 "F.SilkS" user "Ref Des/Silkscreen Top")
		(7 "B.SilkS" user "Ref Des/Silkscreen Bottom")
		(1 "F.Mask" user "Board Geometry/Soldermask Top")
		(3 "B.Mask" user "Board Geometry/Soldermask Bottom")
		(17 "Dwgs.User" user "User.Drawings")
		(19 "Cmts.User" user "User.Comments")
		(21 "Eco1.User" user "User.Eco1")
		(23 "Eco2.User" user "User.Eco2")
		(25 "Edge.Cuts" user "Board Geometry/Outline")
		(27 "Margin" user)
		(31 "F.CrtYd" user "Package Geometry/Place Bound Top")
		(29 "B.CrtYd" user "Package Geometry/Place Bound Bottom")
		(35 "F.Fab" user "Ref Des/Assembly Top")
		(33 "B.Fab" user "Ref Des/Assembly Bottom")
	)
	(footprint ""
		(layer "B.Cu")
		(at 339.244686 -45.481748 180)
		(property "Reference" "C1256"
			(at 0 0 0)
			(layer "B.SilkS")
			(hide yes)
			(effects
				(font
					(size 1.27 1.27)
				)
				(justify mirror)
			)
		)
		(property "Value" ""
			(at 0 0 0)
			(layer "B.Fab")
			(effects
				(font
					(size 1.27 1.27)
				)
				(justify mirror)
			)
		)
		(duplicate_pad_numbers_are_jumpers no)
		(fp_line
			(start 0.7874 0.4064)
			(end 0.7874 -0.4064)
			(stroke
				(width 0.1524)
				(type default)
			)
			(layer "B.SilkS")
		)
		(fp_line
			(start 0.7874 -0.4064)
			(end -0.7874 -0.4064)
			(stroke
				(width 0.1524)
				(type default)
			)
			(layer "B.SilkS")
		)
		(fp_line
			(start -0.7874 0.4064)
			(end 0.7874 0.4064)
			(stroke
				(width 0.1524)
				(type default)
			)
			(layer "B.SilkS")
		)
		(fp_line
			(start -0.7874 -0.4064)
			(end -0.7874 0.4064)
			(stroke
				(width 0.1524)
				(type default)
			)
			(layer "B.SilkS")
		)
		(fp_line
			(start 0.67945 0.3048)
			(end 0.67945 -0.305054)
			(stroke
				(width 0.1)
				(type default)
			)
			(layer "B.Fab")
		)
		(fp_line
			(start 0.67945 -0.305054)
			(end 0.12065 -0.305054)
			(stroke
				(width 0.1)
				(type default)
			)
			(layer "B.Fab")
		)
		(fp_line
			(start 0.12065 0.3048)
			(end 0.67945 0.3048)
			(stroke
				(width 0.1)
				(type default)
			)
			(layer "B.Fab")
		)
		(fp_line
			(start 0.12065 0.2794)
			(end 0.12065 0.3048)
			(stroke
				(width 0.1)
				(type default)
			)
			(layer "B.Fab")
		)
		(fp_line
			(start 0.12065 -0.2794)
			(end -0.12065 -0.2794)
			(stroke
				(width 0.1)
				(type default)
			)
			(layer "B.Fab")
		)
		(fp_line
			(start 0.12065 -0.305054)
			(end 0.12065 -0.2794)
			(stroke
				(width 0.1)
				(type default)
			)
			(layer "B.Fab")
		)
		(fp_line
			(start -0.120396 0.3048)
			(end -0.120396 0.2794)
			(stroke
				(width 0.1)
				(type default)
			)
			(layer "B.Fab")
		)
		(fp_line
			(start -0.120396 0.2794)
			(end 0.12065 0.2794)
			(stroke
				(width 0.1)
				(type default)
			)
			(layer "B.Fab")
		)
		(fp_line
			(start -0.12065 -0.2794)
			(end -0.12065 -0.3048)
			(stroke
				(width 0.1)
				(type default)
			)
			(layer "B.Fab")
		)
		(fp_line
			(start -0.12065 -0.3048)
			(end -0.67945 -0.3048)
			(stroke
				(width 0.1)
				(type default)
			)
			(layer "B.Fab")
		)
		(fp_line
			(start -0.67945 0.3048)
			(end -0.120396 0.3048)
			(stroke
				(width 0.1)
				(type default)
			)
			(layer "B.Fab")
		)
		(fp_line
			(start -0.67945 -0.3048)
			(end -0.67945 0.3048)
			(stroke
				(width 0.1)
				(type default)
			)
			(layer "B.Fab")
		)
		(pad "1" smd circle
			(at 0.40005 0)
			(size 0 0)
			(layers "B.Cu" "B.Mask" "B.Paste")
			(net "P1V05_PCH_PLL_AUX")
		)
		(pad "2" smd circle
			(at -0.40005 0)
			(size 0 0)
			(layers "B.Cu" "B.Mask" "B.Paste")
			(net "GND")
		)
	)
	(footprint ""
		(layer "B.Cu")
		(at 429.40224 -108.867448 90)
		(property "Reference" "R3785"
			(at 0 0 90)
			(layer "B.SilkS")
			(hide yes)
			(effects
				(font
					(size 1.27 1.27)
				)
				(justify mirror)
			)
		)
		(property "Value" ""
			(at 0 0 90)
			(layer "B.Fab")
			(effects
				(font
					(size 1.27 1.27)
				)
				(justify mirror)
			)
		)
		(duplicate_pad_numbers_are_jumpers no)
		(fp_line
			(start 0.7874 -0.4064)
			(end -0.7874 -0.4064)
			(stroke
				(width 0.1524)
				(type default)
			)
			(layer "B.SilkS")
		)
		(fp_line
			(start -0.7874 -0.4064)
			(end -0.7874 0.4064)
			(stroke
				(width 0.1524)
				(type default)
			)
			(layer "B.SilkS")
		)
		(fp_line
			(start 0.7874 0.4064)
			(end 0.7874 -0.4064)
			(stroke
				(width 0.1524)
				(type default)
			)
			(layer "B.SilkS")
		)
		(fp_line
			(start -0.7874 0.4064)
			(end 0.7874 0.4064)
			(stroke
				(width 0.1524)
				(type default)
			)
			(layer "B.SilkS")
		)
		(fp_line
			(start 0.67945 -0.305054)
			(end 0.12065 -0.305054)
			(stroke
				(width 0.1)
				(type default)
			)
			(layer "B.Fab")
		)
		(fp_line
			(start 0.12065 -0.305054)
			(end 0.12065 -0.2794)
			(stroke
				(width 0.1)
				(type default)
			)
			(layer "B.Fab")
		)
		(fp_line
			(start -0.12065 -0.3048)
			(end -0.67945 -0.3048)
			(stroke
				(width 0.1)
				(type default)
			)
			(layer "B.Fab")
		)
		(fp_line
			(start -0.67945 -0.3048)
			(end -0.67945 0.3048)
			(stroke
				(width 0.1)
				(type default)
			)
			(layer "B.Fab")
		)
		(fp_line
			(start 0.12065 -0.2794)
			(end -0.12065 -0.2794)
			(stroke
				(width 0.1)
				(type default)
			)
			(layer "B.Fab")
		)
		(fp_line
			(start -0.12065 -0.2794)
			(end -0.12065 -0.3048)
			(stroke
				(width 0.1)
				(type default)
			)
			(layer "B.Fab")
		)
		(fp_line
			(start 0.12065 0.2794)
			(end 0.12065 0.3048)
			(stroke
				(width 0.1)
				(type default)
			)
			(layer "B.Fab")
		)
		(fp_line
			(start -0.120396 0.2794)
			(end 0.12065 0.2794)
			(stroke
				(width 0.1)
				(type default)
			)
			(layer "B.Fab")
		)
		(fp_line
			(start 0.67945 0.3048)
			(end 0.67945 -0.305054)
			(stroke
				(width 0.1)
				(type default)
			)
			(layer "B.Fab")
		)
		(fp_line
			(start 0.12065 0.3048)
			(end 0.67945 0.3048)
			(stroke
				(width 0.1)
				(type default)
			)
			(layer "B.Fab")
		)
		(fp_line
			(start -0.120396 0.3048)
			(end -0.120396 0.2794)
			(stroke
				(width 0.1)
				(type default)
			)
			(layer "B.Fab")
		)
		(fp_line
			(start -0.67945 0.3048)
			(end -0.120396 0.3048)
			(stroke
				(width 0.1)
				(type default)
			)
			(layer "B.Fab")
		)
		(pad "1" smd circle
			(at 0.40005 0 270)
			(size 0 0)
			(layers "B.Cu" "B.Mask" "B.Paste")
			(net "P3V3_OCP_UV_1_R1")
		)
		(pad "2" smd circle
			(at -0.40005 0 270)
			(size 0 0)
			(layers "B.Cu" "B.Mask" "B.Paste")
			(net "P3V3_OCP_UV_1")
		)
	)
)
